# S9S_MB_2U (Grand Teton) — schematic netlist excerpt (pin names and nets, part order shuffled) for the footprints in the layout excerpt that follows; sources: Cadence DE-HDL packaged netlist, KiCad conversion of 03242023_DA0F0TMBIJ0_F0T_Motherboard_J_brd_V01_OCP.brd

J13  SCONN288_ADR50017P130CC  SCONN288_ADR50017-P130CC IO  pkg DDR288S_1-1VXB  page 94
  VIN_BULK0  = P12V_S3_AUX_CPU0_NVDIMM
  RFU0  = TP_CHG_CPU0_DIMM1_FRU_0
  VIN_MGMT  = P3V3_AUX
  HSCL  = I3C_SPD_DDREFGH_CPU0_LVC1_SCL_4
  HSDA  = I3C_SPD_DDREFGH_CPU0_LVC1_SDA
  VSS0  = GND
  DQ0_A  = M_G_CPU0_SA_DQ<0>
  VSS1  = GND
  DQ1_A  = M_G_CPU0_SA_DQ<1>
  VSS2  = GND
  DQS0_A_T  = M_G_CPU0_SA_DQS_DP<0>
  DQS0_A_C  = M_G_CPU0_SA_DQS_DN<0>
  VSS3  = GND
  DQ4_A  = M_G_CPU0_SA_DQ<4>
  VSS4  = GND
  DQ5_A  = M_G_CPU0_SA_DQ<5>
  VSS5  = GND
  DQ8_A  = M_G_CPU0_SA_DQ<8>
  VSS6  = GND
  DQ9_A  = M_G_CPU0_SA_DQ<9>
  VSS7  = GND
  DQS1_A_T  = M_G_CPU0_SA_DQS_DP<1>
  DQS1_A_C  = M_G_CPU0_SA_DQS_DN<1>
  VSS8  = GND
  DQ12_A  = M_G_CPU0_SA_DQ<12>
  VSS9  = GND
  DQ13_A  = M_G_CPU0_SA_DQ<13>
  VSS10  = GND
  DQ16_A  = M_G_CPU0_SA_DQ<16>
  VSS11  = GND
  DQ17_A  = M_G_CPU0_SA_DQ<17>
  VSS12  = GND
  DQS2_A_T  = M_G_CPU0_SA_DQS_DP<2>
  DQS2_A_C  = M_G_CPU0_SA_DQS_DN<2>
  VSS13  = GND
  DQ20_A  = M_G_CPU0_SA_DQ<20>
  VSS14  = GND
  DQ21_A  = M_G_CPU0_SA_DQ<21>
  VSS15  = GND
  DQ24_A  = M_G_CPU0_SA_DQ<24>
  VSS16  = GND
  DQ25_A  = M_G_CPU0_SA_DQ<25>
  VSS17  = GND
  DQS3_A_T  = M_G_CPU0_SA_DQS_DP<3>
  DQS3_A_C  = M_G_CPU0_SA_DQS_DN<3>
  VSS18  = GND
  DQ28_A  = M_G_CPU0_SA_DQ<28>
  VSS19  = GND
  DQ29_A  = M_G_CPU0_SA_DQ<29>
  VSS20  = GND
  CB0_A  = M_G_CPU0_SA_CB<0>
  VSS21  = GND
  CB1_A  = M_G_CPU0_SA_CB<1>
  VSS22  = GND
  DQS4_A_T  = M_G_CPU0_SA_DQS_DP<4>
  DQS4_A_C  = M_G_CPU0_SA_DQS_DN<4>
  VSS23  = GND
  CB4_A  = M_G_CPU0_SA_CB<4>
  VSS24  = GND
  CB5_A  = M_G_CPU0_SA_CB<5>
  VSS25  = GND
  ALERT_N  = M_G_CPU0_ALERT_N
  VSS26  = GND
  CS0_A_N  = M_G_CPU0_SA_CS_N<0>
  VSS27  = GND
  CA0_A  = M_G_CPU0_SA_CA<0>
  VSS28  = GND
  CA2_A  = M_G_CPU0_SA_CA<2>
  VSS29  = GND
  CA4_A  = M_G_CPU0_SA_CA<4>
  VSS30  = GND
  CA6_A  = M_G_CPU0_SA_CA<6>
  VSS31  = GND
  PAR_A  = M_G_CPU0_SA_PAR
  VSS32  = GND
  CA0_B  = M_G_CPU0_SB_CA<0>
  VSS33  = GND
  CA2_B  = M_G_CPU0_SB_CA<2>
  VSS34  = GND
  CA4_B  = M_G_CPU0_SB_CA<4>
  VSS35  = GND
  CA6_B  = M_G_CPU0_SB_CA<6>
  VSS36  = GND
  CS0_B_N  = M_G_CPU0_SB_CS_N<0>
  VSS37  = GND
  \lbd||rsp_a_n\  = M_G_CPU0_SA_RSP<0>
  \lbs||rsp_b_n\  = M_G_CPU0_SB_RSP<0>
  VSS38  = GND
  CB4_B  = M_G_CPU0_SB_CB<4>
  VSS39  = GND
  CB5_B  = M_G_CPU0_SB_CB<5>
  VSS40  = GND
  \dqs9_b_t||tdqs9_b_t||dbi4_b_n\  = M_G_CPU0_SB_DQS_DP<9>
  \dqs9_b_c||tdqs9_b_c\  = M_G_CPU0_SB_DQS_DN<9>
  VSS41  = GND
  CB0_B  = M_G_CPU0_SB_CB<0>
  VSS42  = GND
  CB1_B  = M_G_CPU0_SB_CB<1>
  VSS43  = GND
  DQ0_B  = M_G_CPU0_SB_DQ<0>
  VSS44  = GND
  DQ1_B  = M_G_CPU0_SB_DQ<1>
  VSS45  = GND
  DQS0_B_T  = M_G_CPU0_SB_DQS_DP<0>
  DQS0_B_C  = M_G_CPU0_SB_DQS_DN<0>
  VSS46  = GND
  DQ4_B  = M_G_CPU0_SB_DQ<4>
  VSS47  = GND
  DQ5_B  = M_G_CPU0_SB_DQ<5>
  VSS48  = GND
  DQ8_B  = M_G_CPU0_SB_DQ<8>
  VSS49  = GND
  DQ9_B  = M_G_CPU0_SB_DQ<9>
  VSS50  = GND
  DQS1_B_T  = M_G_CPU0_SB_DQS_DP<1>
  DQS1_B_C  = M_G_CPU0_SB_DQS_DN<1>
  VSS51  = GND
  DQ12_B  = M_G_CPU0_SB_DQ<12>
  VSS52  = GND
  DQ13_B  = M_G_CPU0_SB_DQ<13>
  VSS53  = GND
  DQ16_B  = M_G_CPU0_SB_DQ<16>
  VSS54  = GND
  DQ17_B  = M_G_CPU0_SB_DQ<17>
  VSS55  = GND
  DQS2_B_T  = M_G_CPU0_SB_DQS_DP<2>
  DQS2_B_C  = M_G_CPU0_SB_DQS_DN<2>
  VSS56  = GND
  DQ20_B  = M_G_CPU0_SB_DQ<20>
  VSS57  = GND
  DQ21_B  = M_G_CPU0_SB_DQ<21>
  VSS58  = GND
  DQ24_B  = M_G_CPU0_SB_DQ<24>
  VSS59  = GND
  DQ25_B  = M_G_CPU0_SB_DQ<25>
  VSS60  = GND
  DQS3_B_T  = M_G_CPU0_SB_DQS_DP<3>
  DQS3_B_C  = M_G_CPU0_SB_DQS_DN<3>
  VSS61  = GND
  DQ28_B  = M_G_CPU0_SB_DQ<28>
  VSS62  = GND
  DQ29_B  = M_G_CPU0_SB_DQ<29>
  VSS63  = GND
  RFU1  = TP_CHG_CPU0_DIMM1_FRU_1
  VIN_BULK1  = P12V_S3_AUX_CPU0_NVDIMM
  VIN_BULK2  = P12V_S3_AUX_CPU0_NVDIMM
  \pwr_good||fail_n\  = PWRGD_CHG_CPU0_DIMM1
  HSA  = PD_CHG_CPU0_DIMM1_SAA
  RFU2  = TP_CHG_CPU0_DIMM1_FRU_2
  RFU3  = TP_CHG_CPU0_DIMM1_FRU_3
  VSS64  = GND
  DQ2_A  = M_G_CPU0_SA_DQ<2>
  VSS65  = GND
  DQ3_A  = M_G_CPU0_SA_DQ<3>
  VSS66  = GND
  \dqs5_a_c||tdqs5_a_c||dqs5_a_t||tdqs5_a_t\  = M_G_CPU0_SA_DQS_DN<5>
  \dqs5_a_t||tdqs5_a_t\  = M_G_CPU0_SA_DQS_DP<5>
  VSS67  = GND
  DQ6_A  = M_G_CPU0_SA_DQ<6>
  VSS68  = GND
  DQ7_A  = M_G_CPU0_SA_DQ<7>
  VSS69  = GND
  DQ10_A  = M_G_CPU0_SA_DQ<10>
  VSS70  = GND
  DQ11_A  = M_G_CPU0_SA_DQ<11>
  VSS71  = GND
  \dqs6_a_c||tdqs6_a_c||dqs6_a_t||tdqs6_a_t\  = M_G_CPU0_SA_DQS_DN<6>
  \dqs6_a_t||tdqs6_a_t\  = M_G_CPU0_SA_DQS_DP<6>
  VSS72  = GND
  DQ14_A  = M_G_CPU0_SA_DQ<14>
  VSS73  = GND
  DQ15_A  = M_G_CPU0_SA_DQ<15>
  VSS74  = GND
  DQ18_A  = M_G_CPU0_SA_DQ<18>
  VSS75  = GND
  DQ19_A  = M_G_CPU0_SA_DQ<19>
  VSS76  = GND
  \dqs7_a_c||tdqs7_a_c\  = M_G_CPU0_SA_DQS_DN<7>
  \dqs7_a_t||tdqs7_a_t\  = M_G_CPU0_SA_DQS_DP<7>
  VSS77  = GND
  DQ22_A  = M_G_CPU0_SA_DQ<22>
  VSS78  = GND
  DQ23_A  = M_G_CPU0_SA_DQ<23>
  VSS79  = GND
  DQ26_A  = M_G_CPU0_SA_DQ<26>
  VSS80  = GND
  DQ27_A  = M_G_CPU0_SA_DQ<27>
  VSS81  = GND
  \dqs8_a_c||tdqs8_a_c\  = M_G_CPU0_SA_DQS_DN<8>
  \dqs8_a_t||tdqs8_a_t\  = M_G_CPU0_SA_DQS_DP<8>
  VSS82  = GND
  DQ30_A  = M_G_CPU0_SA_DQ<30>
  VSS83  = GND
  DQ31_A  = M_G_CPU0_SA_DQ<31>
  VSS84  = GND
  CB2_A  = M_G_CPU0_SA_CB<2>
  VSS85  = GND
  CB3_A  = M_G_CPU0_SA_CB<3>
  VSS86  = GND
  \dqs9_a_c||tdqs9_a_c\  = M_G_CPU0_SA_DQS_DN<9>
  \dqs9_a_t||tdqs9_a_t\  = M_G_CPU0_SA_DQS_DP<9>
  VSS87  = GND
  CB6_A  = M_G_CPU0_SA_CB<6>
  VSS88  = GND
  CB7_A  = M_G_CPU0_SA_CB<7>
  VSS89  = GND
  RESET_N  = RST_M_GH_CPU0_FPGA_N
  VSS90  = GND
  CS1_A_N  = M_G_CPU0_SA_CS_N<1>
  VSS91  = GND
  CA1_A  = M_G_CPU0_SA_CA<1>
  VSS92  = GND
  CA3_A  = M_G_CPU0_SA_CA<3>
  VSS93  = GND
  CA5_A  = M_G_CPU0_SA_CA<5>
  VSS94  = GND
  CK_T  = M_G_CPU0_CLK_DP<0>
  CK_C  = M_G_CPU0_CLK_DN<0>
  VSS95  = GND
  RFU4  = TP_CHG_CPU0_DIMM1_FRU_4
  CA1_B  = M_G_CPU0_SB_CA<1>
  VSS96  = GND
  CA3_B  = M_G_CPU0_SB_CA<3>
  VSS97  = GND
  CA5_B  = M_G_CPU0_SB_CA<5>
  VSS98  = GND
  PAR_B  = M_G_CPU0_SB_PAR
  VSS99  = GND
  CS1_B_N  = M_G_CPU0_SB_CS_N<1>
  VSS100  = GND
  RFU5  = TP_CHG_CPU0_DIMM1_FRU_5
  RFU6  = TP_CHG_CPU0_DIMM1_FRU_6
  VSS101  = GND
  CB6_B  = M_G_CPU0_SB_CB<6>
  VSS102  = GND
  CB7_B  = M_G_CPU0_SB_CB<7>
  VSS103  = GND
  DQS4_B_C  = M_G_CPU0_SB_DQS_DN<4>
  DQS4_B_T  = M_G_CPU0_SB_DQS_DP<4>
  VSS104  = GND
  CB2_B  = M_G_CPU0_SB_CB<2>
  VSS105  = GND
  CB3_B  = M_G_CPU0_SB_CB<3>
  VSS106  = GND
  DQ2_B  = M_G_CPU0_SB_DQ<2>
  VSS107  = GND
  DQ3_B  = M_G_CPU0_SB_DQ<3>
  VSS108  = GND
  \dqs5_b_c||tdqs5_b_c\  = M_G_CPU0_SB_DQS_DN<5>
  \dqs5_b_t||tdqs5_b_t\  = M_G_CPU0_SB_DQS_DP<5>
  VSS109  = GND
  DQ6_B  = M_G_CPU0_SB_DQ<6>
  VSS110  = GND
  DQ7_B  = M_G_CPU0_SB_DQ<7>
  VSS111  = GND
  DQ10_B  = M_G_CPU0_SB_DQ<10>
  VSS112  = GND
  DQ11_B  = M_G_CPU0_SB_DQ<11>
  VSS113  = GND
  \dqs6_b_c||tdqs6_b_c\  = M_G_CPU0_SB_DQS_DN<6>
  \dqs6_b_t||tdqs6_b_t\  = M_G_CPU0_SB_DQS_DP<6>
  VSS114  = GND
  DQ14_B  = M_G_CPU0_SB_DQ<14>
  VSS115  = GND
  DQ15_B  = M_G_CPU0_SB_DQ<15>
  VSS116  = GND
  DQ18_B  = M_G_CPU0_SB_DQ<18>
  VSS117  = GND
  DQ19_B  = M_G_CPU0_SB_DQ<19>
  VSS118  = GND
  \dqs7_b_c||tdqs7_b_c\  = M_G_CPU0_SB_DQS_DN<7>
  \dqs7_b_t||tdqs7_b_t\  = M_G_CPU0_SB_DQS_DP<7>
  VSS119  = GND
  DQ22_B  = M_G_CPU0_SB_DQ<22>
  VSS120  = GND
  DQ23_B  = M_G_CPU0_SB_DQ<23>
  VSS121  = GND
  DQ26_B  = M_G_CPU0_SB_DQ<26>
  VSS122  = GND
  DQ27_B  = M_G_CPU0_SB_DQ<27>
  VSS123  = GND
  \dqs8_b_c||tdqs8_b_c\  = M_G_CPU0_SB_DQS_DN<8>
  \dqs8_b_t||tdqs8_b_t\  = M_G_CPU0_SB_DQS_DP<8>
  VSS124  = GND
  DQ30_B  = M_G_CPU0_SB_DQ<30>
  VSS125  = GND
  DQ31_B  = M_G_CPU0_SB_DQ<31>
  VSS126  = GND
  G1  = GND
  G2  = GND
  G3  = GND

(kicad_pcb
	(version 20260206)
	(generator "pcbnew")
	(generator_version "10.0")
	(general
		(thickness 1.6)
		(legacy_teardrops no)
	)
	(paper "A4")
	(title_block
		(title "03242023_DA0F0TMBIJ0_F0T_Motherboard_J_brd_V01_OCP.brd")
		(comment 1 "Grand Teton / footprint 1368 of 6105 (J13), pads 275-291 of 291")
	)
	(layers
		(0 "F.Cu" signal "TOP")
		(4 "In1.Cu" signal "GND")
		(6 "In2.Cu" signal "IN1")
		(8 "In3.Cu" signal "GND1")
		(10 "In4.Cu" signal "IN2")
		(12 "In5.Cu" signal "GND2")
		(14 "In6.Cu" signal "IN3")
		(16 "In7.Cu" signal "GND3")
		(18 "In8.Cu" signal "VCC")
		(20 "In9.Cu" signal "VCC1")
		(22 "In10.Cu" signal "GND4")
		(24 "In11.Cu" signal "IN4")
		(26 "In12.Cu" signal "GND5")
		(28 "In13.Cu" signal "IN5")
		(30 "In14.Cu" signal "GND6")
		(32 "In15.Cu" signal "IN6")
		(34 "In16.Cu" signal "GND7")
		(2 "B.Cu" signal "BOTTOM")
		(9 "F.Adhes" user "F.Adhesive")
		(11 "B.Adhes" user "B.Adhesive")
		(13 "F.Paste" user "Package Geometry/Pastemask Top")
		(15 "B.Paste" user "Package Geometry/Pastemask Bottom")
		(5 "F.SilkS" user "Ref Des/Silkscreen Top")
		(7 "B.SilkS" user "Ref Des/Silkscreen Bottom")
		(1 "F.Mask" user "Board Geometry/Soldermask Top")
		(3 "B.Mask" user "Board Geometry/Soldermask Bottom")
		(17 "Dwgs.User" user "User.Drawings")
		(19 "Cmts.User" user "User.Comments")
		(21 "Eco1.User" user "User.Eco1")
		(23 "Eco2.User" user "User.Eco2")
		(25 "Edge.Cuts" user "Board Geometry/Outline")
		(27 "Margin" user)
		(31 "F.CrtYd" user "Package Geometry/Place Bound Top")
		(29 "B.CrtYd" user "Package Geometry/Place Bound Bottom")
		(35 "F.Fab" user "Ref Des/Assembly Top")
		(33 "B.Fab" user "Ref Des/Assembly Bottom")
	)
	(footprint ""
		(layer "F.Cu")
		(at 446.522348 -258.091686)
		(property "Reference" "J13"
			(at -3.683 -81.702148 0)
			(unlocked yes)
			(layer "F.SilkS")
			(effects
				(font
					(size 0.7874 0.5842)
					(thickness 0.1524)
				)
				(justify left)
			)
		)
		(property "Value" ""
			(at 0 0 0)
			(layer "F.Fab")
			(effects
				(font
					(size 1.27 1.27)
				)
			)
		)
		(duplicate_pad_numbers_are_jumpers no)
		(pad "275" smd rect
			(at 2.050034 52.274978 270)
			(size 0.519938 1.4986)
			(layers "F.Cu" "F.Mask" "F.Paste")
			(net "GND")
		)
		(pad "276" smd rect
			(at 2.050034 53.125116 270)
			(size 0.519938 1.4986)
			(layers "F.Cu" "F.Mask" "F.Paste")
			(net "M_G_CPU0_SB_DQ<23>")
		)
		(pad "277" smd rect
			(at 2.050034 53.975 270)
			(size 0.519938 1.4986)
			(layers "F.Cu" "F.Mask" "F.Paste")
			(net "GND")
		)
		(pad "278" smd rect
			(at 2.050034 54.824884 270)
			(size 0.519938 1.4986)
			(layers "F.Cu" "F.Mask" "F.Paste")
			(net "M_G_CPU0_SB_DQ<26>")
		)
		(pad "279" smd rect
			(at 2.050034 55.675022 270)
			(size 0.519938 1.4986)
			(layers "F.Cu" "F.Mask" "F.Paste")
			(net "GND")
		)
		(pad "280" smd rect
			(at 2.050034 56.524906 270)
			(size 0.519938 1.4986)
			(layers "F.Cu" "F.Mask" "F.Paste")
			(net "M_G_CPU0_SB_DQ<27>")
		)
		(pad "281" smd rect
			(at 2.050034 57.375044 270)
			(size 0.519938 1.4986)
			(layers "F.Cu" "F.Mask" "F.Paste")
			(net "GND")
		)
		(pad "282" smd rect
			(at 2.050034 58.224928 270)
			(size 0.519938 1.4986)
			(layers "F.Cu" "F.Mask" "F.Paste")
			(net "M_G_CPU0_SB_DQS_DN<8>")
		)
		(pad "283" smd rect
			(at 2.050034 59.075066 270)
			(size 0.519938 1.4986)
			(layers "F.Cu" "F.Mask" "F.Paste")
			(net "M_G_CPU0_SB_DQS_DP<8>")
		)
		(pad "284" smd rect
			(at 2.050034 59.92495 270)
			(size 0.519938 1.4986)
			(layers "F.Cu" "F.Mask" "F.Paste")
			(net "GND")
		)
		(pad "285" smd rect
			(at 2.050034 60.775088 270)
			(size 0.519938 1.4986)
			(layers "F.Cu" "F.Mask" "F.Paste")
			(net "M_G_CPU0_SB_DQ<30>")
		)
		(pad "286" smd rect
			(at 2.050034 61.624972 270)
			(size 0.519938 1.4986)
			(layers "F.Cu" "F.Mask" "F.Paste")
			(net "GND")
		)
		(pad "287" smd rect
			(at 2.050034 62.47511 270)
			(size 0.519938 1.4986)
			(layers "F.Cu" "F.Mask" "F.Paste")
			(net "M_G_CPU0_SB_DQ<31>")
		)
		(pad "288" smd rect
			(at 2.050034 63.324994 270)
			(size 0.519938 1.4986)
			(layers "F.Cu" "F.Mask" "F.Paste")
			(net "GND")
		)
		(pad "G1" thru_hole oval
			(at 0 -68.97497)
			(size 2.8194 1.5748)
			(drill oval 2.4384 1.1938)
			(layers "*.Cu" "*.Mask")
			(remove_unused_layers no)
			(net "GND")
			(clearance 0.127)
			(thermal_gap 0.127)
		)
		(pad "G2" thru_hole oval
			(at 0 3.875024)
			(size 2.8194 1.5748)
			(drill oval 2.4384 1.1938)
			(layers "*.Cu" "*.Mask")
			(remove_unused_layers no)
			(net "GND")
			(clearance 0.127)
			(thermal_gap 0.127)
		)
		(pad "G3" thru_hole oval
			(at 0 68.97497)
			(size 2.8194 1.5748)
			(drill oval 2.4384 1.1938)
			(layers "*.Cu" "*.Mask")
			(remove_unused_layers no)
			(net "GND")
			(clearance 0.127)
			(thermal_gap 0.127)
		)
	)
)
